(kicad_pcb
	(version 20260206)
	(generator "pcbnew")
	(generator_version "10.0")
	(general
		(thickness 1.6)
		(legacy_teardrops no)
	)
	(paper "A4")
	(title_block
		(title "peb — Lightning_PEB_BRD.brd")
		(comment 1 "Lightning (Wiwynn / Facebook NVMe JBOF) / footprints 1352-1359 of 2563")
	)
	(layers
		(0 "F.Cu" signal "TOP")
		(4 "In1.Cu" signal "L2GND")
		(6 "In2.Cu" signal "L3")
		(8 "In3.Cu" signal "L4VCC")
		(10 "In4.Cu" signal "L5VCC")
		(12 "In5.Cu" signal "L6")
		(14 "In6.Cu" signal "L7GND")
		(2 "B.Cu" signal "BOTTOM")
		(9 "F.Adhes" user "F.Adhesive")
		(11 "B.Adhes" user "B.Adhesive")
		(13 "F.Paste" user "Package Geometry/Pastemask Top")
		(15 "B.Paste" user "Package Geometry/Pastemask Bottom")
		(5 "F.SilkS" user "Ref Des/Silkscreen Top")
		(7 "B.SilkS" user "Ref Des/Silkscreen Bottom")
		(1 "F.Mask" user "Board Geometry/Soldermask Top")
		(3 "B.Mask" user "Board Geometry/Soldermask Bottom")
		(17 "Dwgs.User" user "User.Drawings")
		(19 "Cmts.User" user "User.Comments")
		(21 "Eco1.User" user "User.Eco1")
		(23 "Eco2.User" user "User.Eco2")
		(25 "Edge.Cuts" user "Board Geometry/Outline")
		(27 "Margin" user)
		(31 "F.CrtYd" user "Package Geometry/Place Bound Top")
		(29 "B.CrtYd" user "Package Geometry/Place Bound Bottom")
		(35 "F.Fab" user "Ref Des/Assembly Top")
		(33 "B.Fab" user "Ref Des/Assembly Bottom")
	)
	(footprint ""
		(layer "F.Cu")
		(at 310.007 -66.2686)
		(property "Reference" "PG42"
			(at 0 0 0)
			(layer "F.SilkS")
			(hide yes)
			(effects
				(font
					(size 1.27 1.27)
				)
			)
		)
		(property "Value" "GAP-CLOSE-PWR-3-GP"
			(at 0.0254 -6.5786 0)
			(unlocked yes)
			(layer "F.Fab")
			(hide yes)
			(effects
				(font
					(size 1.016 1.016)
					(thickness 0.1524)
				)
			)
		)
		(property "Device Type" "GAP-CLOSE-PWR-3"
			(at 0.0254 -8.255 0)
			(unlocked yes)
			(layer "F.Fab")
			(hide yes)
			(effects
				(font
					(size 1.016 1.016)
					(thickness 0.1524)
				)
			)
		)
		(duplicate_pad_numbers_are_jumpers no)
		(fp_rect
			(start -0.7112 0.4572)
			(end 0.7112 -0.4572)
			(stroke
				(width 0)
				(type default)
			)
			(fill no)
			(layer "F.CrtYd")
		)
		(fp_poly
			(pts
				(xy -0.7112 -0.4572) (xy 0.7112 -0.4572) (xy 0.7112 0.4572) (xy -0.7112 0.4572)
			)
			(stroke
				(width 0)
				(type default)
			)
			(fill no)
			(layer "F.Fab")
		)
		(pad "1" smd rect
			(at -0.3048 0)
			(size 0.6604 0.762)
			(layers "F.Cu" "F.Mask" "F.Paste")
			(net "DUT_VDD")
		)
		(pad "2" smd rect
			(at 0.3048 0)
			(size 0.6604 0.762)
			(layers "F.Cu" "F.Mask" "F.Paste")
			(net "P0V9_E")
		)
	)
	(footprint ""
		(layer "F.Cu")
		(at 54.983126 -44.20235)
		(property "Reference" "R698"
			(at 0 0 0)
			(layer "F.SilkS")
			(hide yes)
			(effects
				(font
					(size 1.27 1.27)
				)
			)
		)
		(property "Value" "56R6J-GP"
			(at -0.0508 -4.8514 0)
			(unlocked yes)
			(layer "F.Fab")
			(hide yes)
			(effects
				(font
					(size 1.016 1.016)
					(thickness 0.1524)
				)
			)
		)
		(property "Device Type" "R1206H26"
			(at 0 -6.3754 0)
			(unlocked yes)
			(layer "F.Fab")
			(hide yes)
			(effects
				(font
					(size 1.016 1.016)
					(thickness 0.1524)
				)
			)
		)
		(duplicate_pad_numbers_are_jumpers no)
		(fp_line
			(start -1.016 -2.2352)
			(end 1.016 -2.2352)
			(stroke
				(width 0.1524)
				(type default)
			)
			(layer "F.SilkS")
		)
		(fp_line
			(start -1.016 2.2352)
			(end -1.016 -2.2352)
			(stroke
				(width 0.1524)
				(type default)
			)
			(layer "F.SilkS")
		)
		(fp_line
			(start 1.016 -2.2352)
			(end 1.016 2.2352)
			(stroke
				(width 0.1524)
				(type default)
			)
			(layer "F.SilkS")
		)
		(fp_line
			(start 1.016 2.2352)
			(end -1.016 2.2352)
			(stroke
				(width 0.1524)
				(type default)
			)
			(layer "F.SilkS")
		)
		(fp_rect
			(start -1.0922 2.3114)
			(end 1.0922 -2.3114)
			(stroke
				(width 0)
				(type default)
			)
			(fill no)
			(layer "F.CrtYd")
		)
		(fp_poly
			(pts
				(xy -1.0922 -2.3114) (xy 1.0922 -2.3114) (xy 1.0922 2.3114) (xy -1.0922 2.3114)
			)
			(stroke
				(width 0)
				(type default)
			)
			(fill no)
			(layer "F.Fab")
		)
		(pad "1" smd rect
			(at 0 -1.397)
			(size 1.651 1.27)
			(layers "F.Cu" "F.Mask" "F.Paste")
			(net "P3V3_STBY")
		)
		(pad "2" smd rect
			(at 0 1.397)
			(size 1.651 1.27)
			(layers "F.Cu" "F.Mask" "F.Paste")
			(net "Q43_C")
		)
	)
	(footprint ""
		(layer "F.Cu")
		(at 208.852008 -4.064)
		(property "Reference" "R682"
			(at 0 0 0)
			(layer "F.SilkS")
			(hide yes)
			(effects
				(font
					(size 1.27 1.27)
				)
			)
		)
		(property "Value" "100KR2F-L1-GP"
			(at 0.064008 -3.993896 0)
			(unlocked yes)
			(layer "F.Fab")
			(hide yes)
			(effects
				(font
					(size 1.016 1.016)
					(thickness 0.1524)
				)
			)
		)
		(property "Device Type" "R402H16"
			(at 0.064008 -5.517896 0)
			(unlocked yes)
			(layer "F.Fab")
			(hide yes)
			(effects
				(font
					(size 1.016 1.016)
					(thickness 0.1524)
				)
			)
		)
		(duplicate_pad_numbers_are_jumpers no)
		(fp_line
			(start -0.508 -0.9398)
			(end -0.508 0.9398)
			(stroke
				(width 0.1524)
				(type default)
			)
			(layer "F.SilkS")
		)
		(fp_line
			(start 0.508 -0.9398)
			(end -0.508 -0.9398)
			(stroke
				(width 0.1524)
				(type default)
			)
			(layer "F.SilkS")
		)
		(fp_rect
			(start -0.508 0.9398)
			(end 0.508 -0.9398)
			(stroke
				(width 0)
				(type default)
			)
			(fill no)
			(layer "F.CrtYd")
		)
		(fp_rect
			(start -0.508 0.9398)
			(end 0.508 -0.9398)
			(stroke
				(width 0)
				(type default)
			)
			(fill no)
			(layer "F.Fab")
		)
		(pad "1" smd custom
			(at 0 -0.4445)
			(size 0.1397 0.1397)
			(layers "F.Cu" "F.Mask" "F.Paste")
			(net "HOST8_RST_N")
			(options
				(clearance outline)
				(anchor circle)
			)
			(primitives
				(gr_poly
					(pts
						(arc
							(start -0.1778 -0.2794)
							(mid -0.249642 -0.249642)
							(end -0.2794 -0.1778)
						)
						(arc
							(start -0.2794 0.1778)
							(mid -0.249642 0.249642)
							(end -0.1778 0.2794)
						)
						(arc
							(start 0.1778 0.2794)
							(mid 0.249642 0.249642)
							(end 0.2794 0.1778)
						)
						(arc
							(start 0.2794 -0.1778)
							(mid 0.249642 -0.249642)
							(end 0.1778 -0.2794)
						)
					)
					(width 0)
					(fill yes)
				)
			)
		)
		(pad "2" smd custom
			(at 0 0.4445)
			(size 0.1397 0.1397)
			(layers "F.Cu" "F.Mask" "F.Paste")
			(net "GND")
			(options
				(clearance outline)
				(anchor circle)
			)
			(primitives
				(gr_poly
					(pts
						(arc
							(start -0.1778 -0.2794)
							(mid -0.249642 -0.249642)
							(end -0.2794 -0.1778)
						)
						(arc
							(start -0.2794 0.1778)
							(mid -0.249642 0.249642)
							(end -0.1778 0.2794)
						)
						(arc
							(start 0.1778 0.2794)
							(mid 0.249642 0.249642)
							(end 0.2794 0.1778)
						)
						(arc
							(start 0.2794 -0.1778)
							(mid 0.249642 -0.249642)
							(end 0.1778 -0.2794)
						)
					)
					(width 0)
					(fill yes)
				)
			)
		)
	)
	(footprint ""
		(layer "F.Cu")
		(at 13.2842 -194.2846 180)
		(property "Reference" "R9023"
			(at 0 0 180)
			(layer "F.SilkS")
			(hide yes)
			(effects
				(font
					(size 1.27 1.27)
				)
			)
		)
		(property "Value" "22K6R2F-1-GP"
			(at 0.064008 -3.993896 180)
			(unlocked yes)
			(layer "F.Fab")
			(hide yes)
			(effects
				(font
					(size 1.016 1.016)
					(thickness 0.1524)
				)
			)
		)
		(property "Device Type" "R402H16"
			(at 0.064008 -5.517896 180)
			(unlocked yes)
			(layer "F.Fab")
			(hide yes)
			(effects
				(font
					(size 1.016 1.016)
					(thickness 0.1524)
				)
			)
		)
		(duplicate_pad_numbers_are_jumpers no)
		(fp_line
			(start 0.508 -0.9398)
			(end -0.508 -0.9398)
			(stroke
				(width 0.1524)
				(type default)
			)
			(layer "F.SilkS")
		)
		(fp_line
			(start -0.508 -0.9398)
			(end -0.508 0.9398)
			(stroke
				(width 0.1524)
				(type default)
			)
			(layer "F.SilkS")
		)
		(fp_rect
			(start -0.508 0.9398)
			(end 0.508 -0.9398)
			(stroke
				(width 0)
				(type default)
			)
			(fill no)
			(layer "F.CrtYd")
		)
		(fp_rect
			(start -0.508 0.9398)
			(end 0.508 -0.9398)
			(stroke
				(width 0)
				(type default)
			)
			(fill no)
			(layer "F.Fab")
		)
		(pad "1" smd custom
			(at 0 -0.4445 180)
			(size 0.1397 0.1397)
			(layers "F.Cu" "F.Mask" "F.Paste")
			(net "MB0_ISTART_R")
			(options
				(clearance outline)
				(anchor circle)
			)
			(primitives
				(gr_poly
					(pts
						(arc
							(start -0.1778 -0.2794)
							(mid -0.249642 -0.249642)
							(end -0.2794 -0.1778)
						)
						(arc
							(start -0.2794 0.1778)
							(mid -0.249642 0.249642)
							(end -0.1778 0.2794)
						)
						(arc
							(start 0.1778 0.2794)
							(mid 0.249642 0.249642)
							(end 0.2794 0.1778)
						)
						(arc
							(start 0.2794 -0.1778)
							(mid 0.249642 -0.249642)
							(end 0.1778 -0.2794)
						)
					)
					(width 0)
					(fill yes)
				)
			)
		)
		(pad "2" smd custom
			(at 0 0.4445 180)
			(size 0.1397 0.1397)
			(layers "F.Cu" "F.Mask" "F.Paste")
			(net "AGND_CURRENT_MON")
			(options
				(clearance outline)
				(anchor circle)
			)
			(primitives
				(gr_poly
					(pts
						(arc
							(start -0.1778 -0.2794)
							(mid -0.249642 -0.249642)
							(end -0.2794 -0.1778)
						)
						(arc
							(start -0.2794 0.1778)
							(mid -0.249642 0.249642)
							(end -0.1778 0.2794)
						)
						(arc
							(start 0.1778 0.2794)
							(mid 0.249642 0.249642)
							(end 0.2794 0.1778)
						)
						(arc
							(start 0.2794 -0.1778)
							(mid 0.249642 -0.249642)
							(end 0.1778 -0.2794)
						)
					)
					(width 0)
					(fill yes)
				)
			)
		)
	)
	(footprint ""
		(layer "F.Cu")
		(at 286.792162 -212.420454 180)
		(property "Reference" "C93"
			(at 0 0 180)
			(layer "F.SilkS")
			(hide yes)
			(effects
				(font
					(size 1.27 1.27)
				)
			)
		)
		(property "Value" "SCD22U10V2KX-1GP"
			(at 1.1811 -2.7051 180)
			(unlocked yes)
			(layer "F.Fab")
			(hide yes)
			(effects
				(font
					(size 1.016 1.016)
					(thickness 0.1524)
				)
			)
		)
		(property "Device Type" "C402H22"
			(at 1.1811 -4.2291 180)
			(unlocked yes)
			(layer "F.Fab")
			(hide yes)
			(effects
				(font
					(size 1.016 1.016)
					(thickness 0.1524)
				)
			)
		)
		(duplicate_pad_numbers_are_jumpers no)
		(fp_rect
			(start -0.4318 0.9525)
			(end 0.4318 -0.9525)
			(stroke
				(width 0)
				(type default)
			)
			(fill no)
			(layer "F.CrtYd")
		)
		(fp_rect
			(start -0.4318 0.9525)
			(end 0.4318 -0.9525)
			(stroke
				(width 0)
				(type default)
			)
			(fill no)
			(layer "F.Fab")
		)
		(pad "1" smd custom
			(at 0 -0.4445 180)
			(size 0.1524 0.1524)
			(layers "F.Cu" "F.Mask" "F.Paste")
			(net "PCIE_TX_CAP_P30")
			(options
				(clearance outline)
				(anchor circle)
			)
			(primitives
				(gr_poly
					(pts
						(arc
							(start 0.3048 -0.2032)
							(mid 0.275042 -0.275042)
							(end 0.2032 -0.3048)
						)
						(arc
							(start -0.2032 -0.3048)
							(mid -0.275042 -0.275042)
							(end -0.3048 -0.2032)
						)
						(arc
							(start -0.3048 0.2032)
							(mid -0.275042 0.275042)
							(end -0.2032 0.3048)
						)
						(arc
							(start 0.2032 0.3048)
							(mid 0.275042 0.275042)
							(end 0.3048 0.2032)
						)
					)
					(width 0)
					(fill yes)
				)
			)
		)
		(pad "2" smd custom
			(at 0 0.4445 180)
			(size 0.1524 0.1524)
			(layers "F.Cu" "F.Mask" "F.Paste")
			(net "PCIE_TX_P30")
			(options
				(clearance outline)
				(anchor circle)
			)
			(primitives
				(gr_poly
					(pts
						(arc
							(start 0.3048 -0.2032)
							(mid 0.275042 -0.275042)
							(end 0.2032 -0.3048)
						)
						(arc
							(start -0.2032 -0.3048)
							(mid -0.275042 -0.275042)
							(end -0.3048 -0.2032)
						)
						(arc
							(start -0.3048 0.2032)
							(mid -0.275042 0.275042)
							(end -0.2032 0.3048)
						)
						(arc
							(start 0.2032 0.3048)
							(mid 0.275042 0.275042)
							(end 0.3048 0.2032)
						)
					)
					(width 0)
					(fill yes)
				)
			)
		)
	)
	(footprint ""
		(layer "F.Cu")
		(at 160.79216 -212.420454 180)
		(property "Reference" "C164"
			(at 0 0 180)
			(layer "F.SilkS")
			(hide yes)
			(effects
				(font
					(size 1.27 1.27)
				)
			)
		)
		(property "Value" "SCD22U10V2KX-1GP"
			(at 1.1811 -2.7051 180)
			(unlocked yes)
			(layer "F.Fab")
			(hide yes)
			(effects
				(font
					(size 1.016 1.016)
					(thickness 0.1524)
				)
			)
		)
		(property "Device Type" "C402H22"
			(at 1.1811 -4.2291 180)
			(unlocked yes)
			(layer "F.Fab")
			(hide yes)
			(effects
				(font
					(size 1.016 1.016)
					(thickness 0.1524)
				)
			)
		)
		(duplicate_pad_numbers_are_jumpers no)
		(fp_rect
			(start -0.4318 0.9525)
			(end 0.4318 -0.9525)
			(stroke
				(width 0)
				(type default)
			)
			(fill no)
			(layer "F.CrtYd")
		)
		(fp_rect
			(start -0.4318 0.9525)
			(end 0.4318 -0.9525)
			(stroke
				(width 0)
				(type default)
			)
			(fill no)
			(layer "F.Fab")
		)
		(pad "1" smd custom
			(at 0 -0.4445 180)
			(size 0.1524 0.1524)
			(layers "F.Cu" "F.Mask" "F.Paste")
			(net "PCIE_TX_CAP_P52")
			(options
				(clearance outline)
				(anchor circle)
			)
			(primitives
				(gr_poly
					(pts
						(arc
							(start 0.3048 -0.2032)
							(mid 0.275042 -0.275042)
							(end 0.2032 -0.3048)
						)
						(arc
							(start -0.2032 -0.3048)
							(mid -0.275042 -0.275042)
							(end -0.3048 -0.2032)
						)
						(arc
							(start -0.3048 0.2032)
							(mid -0.275042 0.275042)
							(end -0.2032 0.3048)
						)
						(arc
							(start 0.2032 0.3048)
							(mid 0.275042 0.275042)
							(end 0.3048 0.2032)
						)
					)
					(width 0)
					(fill yes)
				)
			)
		)
		(pad "2" smd custom
			(at 0 0.4445 180)
			(size 0.1524 0.1524)
			(layers "F.Cu" "F.Mask" "F.Paste")
			(net "PCIE_TX_P52")
			(options
				(clearance outline)
				(anchor circle)
			)
			(primitives
				(gr_poly
					(pts
						(arc
							(start 0.3048 -0.2032)
							(mid 0.275042 -0.275042)
							(end 0.2032 -0.3048)
						)
						(arc
							(start -0.2032 -0.3048)
							(mid -0.275042 -0.275042)
							(end -0.3048 -0.2032)
						)
						(arc
							(start -0.3048 0.2032)
							(mid -0.275042 0.275042)
							(end -0.2032 0.3048)
						)
						(arc
							(start 0.2032 0.3048)
							(mid 0.275042 0.275042)
							(end 0.3048 0.2032)
						)
					)
					(width 0)
					(fill yes)
				)
			)
		)
	)
	(footprint ""
		(layer "F.Cu")
		(at 284.608016 -212.420454 180)
		(property "Reference" "C95"
			(at 0 0 180)
			(layer "F.SilkS")
			(hide yes)
			(effects
				(font
					(size 1.27 1.27)
				)
			)
		)
		(property "Value" "SCD22U10V2KX-1GP"
			(at 1.1811 -2.7051 180)
			(unlocked yes)
			(layer "F.Fab")
			(hide yes)
			(effects
				(font
					(size 1.016 1.016)
					(thickness 0.1524)
				)
			)
		)
		(property "Device Type" "C402H22"
			(at 1.1811 -4.2291 180)
			(unlocked yes)
			(layer "F.Fab")
			(hide yes)
			(effects
				(font
					(size 1.016 1.016)
					(thickness 0.1524)
				)
			)
		)
		(duplicate_pad_numbers_are_jumpers no)
		(fp_rect
			(start -0.4318 0.9525)
			(end 0.4318 -0.9525)
			(stroke
				(width 0)
				(type default)
			)
			(fill no)
			(layer "F.CrtYd")
		)
		(fp_rect
			(start -0.4318 0.9525)
			(end 0.4318 -0.9525)
			(stroke
				(width 0)
				(type default)
			)
			(fill no)
			(layer "F.Fab")
		)
		(pad "1" smd custom
			(at 0 -0.4445 180)
			(size 0.1524 0.1524)
			(layers "F.Cu" "F.Mask" "F.Paste")
			(net "PCIE_TX_CAP_N31")
			(options
				(clearance outline)
				(anchor circle)
			)
			(primitives
				(gr_poly
					(pts
						(arc
							(start 0.3048 -0.2032)
							(mid 0.275042 -0.275042)
							(end 0.2032 -0.3048)
						)
						(arc
							(start -0.2032 -0.3048)
							(mid -0.275042 -0.275042)
							(end -0.3048 -0.2032)
						)
						(arc
							(start -0.3048 0.2032)
							(mid -0.275042 0.275042)
							(end -0.2032 0.3048)
						)
						(arc
							(start 0.2032 0.3048)
							(mid 0.275042 0.275042)
							(end 0.3048 0.2032)
						)
					)
					(width 0)
					(fill yes)
				)
			)
		)
		(pad "2" smd custom
			(at 0 0.4445 180)
			(size 0.1524 0.1524)
			(layers "F.Cu" "F.Mask" "F.Paste")
			(net "PCIE_TX_N31")
			(options
				(clearance outline)
				(anchor circle)
			)
			(primitives
				(gr_poly
					(pts
						(arc
							(start 0.3048 -0.2032)
							(mid 0.275042 -0.275042)
							(end 0.2032 -0.3048)
						)
						(arc
							(start -0.2032 -0.3048)
							(mid -0.275042 -0.275042)
							(end -0.3048 -0.2032)
						)
						(arc
							(start -0.3048 0.2032)
							(mid -0.275042 0.275042)
							(end -0.2032 0.3048)
						)
						(arc
							(start 0.2032 0.3048)
							(mid 0.275042 0.275042)
							(end 0.3048 0.2032)
						)
					)
					(width 0)
					(fill yes)
				)
			)
		)
	)
	(footprint ""
		(layer "F.Cu")
		(at 6.8072 -189.7126 -90)
		(property "Reference" "R2113"
			(at 0 0 270)
			(layer "F.SilkS")
			(hide yes)
			(effects
				(font
					(size 1.27 1.27)
				)
			)
		)
		(property "Value" "0R2J-2-GP"
			(at 0.064008 -3.993896 270)
			(unlocked yes)
			(layer "F.Fab")
			(hide yes)
			(effects
				(font
					(size 1.016 1.016)
					(thickness 0.1524)
				)
			)
		)
		(property "Device Type" "R402H16"
			(at 0.064008 -5.517896 270)
			(unlocked yes)
			(layer "F.Fab")
			(hide yes)
			(effects
				(font
					(size 1.016 1.016)
					(thickness 0.1524)
				)
			)
		)
		(duplicate_pad_numbers_are_jumpers no)
		(fp_line
			(start -0.508 -0.9398)
			(end -0.508 0.9398)
			(stroke
				(width 0.1524)
				(type default)
			)
			(layer "F.SilkS")
		)
		(fp_line
			(start 0.508 -0.9398)
			(end -0.508 -0.9398)
			(stroke
				(width 0.1524)
				(type default)
			)
			(layer "F.SilkS")
		)
		(fp_rect
			(start -0.508 0.9398)
			(end 0.508 -0.9398)
			(stroke
				(width 0)
				(type default)
			)
			(fill no)
			(layer "F.CrtYd")
		)
		(fp_rect
			(start -0.508 0.9398)
			(end 0.508 -0.9398)
			(stroke
				(width 0)
				(type default)
			)
			(fill no)
			(layer "F.Fab")
		)
		(pad "1" smd custom
			(at 0 -0.4445 270)
			(size 0.1397 0.1397)
			(layers "F.Cu" "F.Mask" "F.Paste")
			(net "MB0_SPISS_PD")
			(options
				(clearance outline)
				(anchor circle)
			)
			(primitives
				(gr_poly
					(pts
						(arc
							(start -0.1778 -0.2794)
							(mid -0.249642 -0.249642)
							(end -0.2794 -0.1778)
						)
						(arc
							(start -0.2794 0.1778)
							(mid -0.249642 0.249642)
							(end -0.1778 0.2794)
						)
						(arc
							(start 0.1778 0.2794)
							(mid 0.249642 0.249642)
							(end 0.2794 0.1778)
						)
						(arc
							(start 0.2794 -0.1778)
							(mid 0.249642 -0.249642)
							(end 0.1778 -0.2794)
						)
					)
					(width 0)
					(fill yes)
				)
			)
		)
		(pad "2" smd custom
			(at 0 0.4445 270)
			(size 0.1397 0.1397)
			(layers "F.Cu" "F.Mask" "F.Paste")
			(net "AGND_CURRENT_MON")
			(options
				(clearance outline)
				(anchor circle)
			)
			(primitives
				(gr_poly
					(pts
						(arc
							(start -0.1778 -0.2794)
							(mid -0.249642 -0.249642)
							(end -0.2794 -0.1778)
						)
						(arc
							(start -0.2794 0.1778)
							(mid -0.249642 0.249642)
							(end -0.1778 0.2794)
						)
						(arc
							(start 0.1778 0.2794)
							(mid 0.249642 0.249642)
							(end 0.2794 0.1778)
						)
						(arc
							(start 0.2794 -0.1778)
							(mid 0.249642 -0.249642)
							(end 0.1778 -0.2794)
						)
					)
					(width 0)
					(fill yes)
				)
			)
		)
	)
)
